# T6G (Grand Teton) — schematic netlist excerpt (pin names and nets, part order shuffled) for the footprints in the layout excerpt that follows; sources: Cadence DE-HDL packaged netlist, KiCad conversion of 04192023_DAF0TMB3IC0_F0TG_MB_C_brd_V02_OCP.brd

PC6806  Q_CAP  100NF 50V 10% X7R  pkg C0402  page 363 : A = P0V9_CPU0_RT_2D ; B = GND
PC168_2  Q_CAP  22UF 4V 20% X6S  pkg C0805  page 205 : A = PVDDIO_P0 ; B = GND
C2382  Q_CAP  22UF 4V 20% X6S  pkg C0402  page 73 : A = PVDDCR_CPU1_P1 ; B = GND

(kicad_pcb
	(version 20260206)
	(generator "pcbnew")
	(generator_version "10.0")
	(general
		(thickness 1.6)
		(legacy_teardrops no)
	)
	(paper "A4")
	(title_block
		(title "04192023_DAF0TMB3IC0_F0TG_MB_C_brd_V02_OCP.brd")
		(comment 1 "Grand Teton / footprints 7423-7425 of 8354")
	)
	(layers
		(0 "F.Cu" signal "TOP")
		(4 "In1.Cu" signal "GND")
		(6 "In2.Cu" signal "IN1")
		(8 "In3.Cu" signal "GND1")
		(10 "In4.Cu" signal "IN2")
		(12 "In5.Cu" signal "GND2")
		(14 "In6.Cu" signal "IN3")
		(16 "In7.Cu" signal "GND3")
		(18 "In8.Cu" signal "VCC")
		(20 "In9.Cu" signal "VCC1")
		(22 "In10.Cu" signal "GND4")
		(24 "In11.Cu" signal "IN4")
		(26 "In12.Cu" signal "GND5")
		(28 "In13.Cu" signal "IN5")
		(30 "In14.Cu" signal "GND6")
		(32 "In15.Cu" signal "IN6")
		(34 "In16.Cu" signal "GND7")
		(2 "B.Cu" signal "BOTTOM")
		(9 "F.Adhes" user "F.Adhesive")
		(11 "B.Adhes" user "B.Adhesive")
		(13 "F.Paste" user "Package Geometry/Pastemask Top")
		(15 "B.Paste" user "Package Geometry/Pastemask Bottom")
		(5 "F.SilkS" user "Ref Des/Silkscreen Top")
		(7 "B.SilkS" user "Ref Des/Silkscreen Bottom")
		(1 "F.Mask" user "Board Geometry/Soldermask Top")
		(3 "B.Mask" user "Board Geometry/Soldermask Bottom")
		(17 "Dwgs.User" user "User.Drawings")
		(19 "Cmts.User" user "User.Comments")
		(21 "Eco1.User" user "User.Eco1")
		(23 "Eco2.User" user "User.Eco2")
		(25 "Edge.Cuts" user "Board Geometry/Outline")
		(27 "Margin" user)
		(31 "F.CrtYd" user "Package Geometry/Place Bound Top")
		(29 "B.CrtYd" user "Package Geometry/Place Bound Bottom")
		(35 "F.Fab" user "Ref Des/Assembly Top")
		(33 "B.Fab" user "Ref Des/Assembly Bottom")
	)
	(footprint ""
		(layer "B.Cu")
		(at 291.849048 -337.984846 -90)
		(property "Reference" "PC168_2"
			(at 0 0 90)
			(layer "B.SilkS")
			(hide yes)
			(effects
				(font
					(size 1.27 1.27)
				)
				(justify mirror)
			)
		)
		(property "Value" ""
			(at 0 0 90)
			(layer "B.Fab")
			(effects
				(font
					(size 1.27 1.27)
				)
				(justify mirror)
			)
		)
		(duplicate_pad_numbers_are_jumpers no)
		(fp_line
			(start -1.524 0.762)
			(end 1.524 0.762)
			(stroke
				(width 0.1524)
				(type default)
			)
			(layer "B.SilkS")
		)
		(fp_line
			(start 1.524 0.762)
			(end 1.524 -0.762)
			(stroke
				(width 0.1524)
				(type default)
			)
			(layer "B.SilkS")
		)
		(fp_line
			(start -1.524 -0.762)
			(end -1.524 0.762)
			(stroke
				(width 0.1524)
				(type default)
			)
			(layer "B.SilkS")
		)
		(fp_line
			(start 1.524 -0.762)
			(end -1.524 -0.762)
			(stroke
				(width 0.1524)
				(type default)
			)
			(layer "B.SilkS")
		)
		(fp_line
			(start -1.1049 0.724916)
			(end -1.1049 -0.724916)
			(stroke
				(width 0.1)
				(type default)
			)
			(layer "B.Fab")
		)
		(fp_line
			(start 1.1049 0.724916)
			(end -1.1049 0.724916)
			(stroke
				(width 0.1)
				(type default)
			)
			(layer "B.Fab")
		)
		(fp_line
			(start -1.1049 -0.724916)
			(end 1.1049 -0.724916)
			(stroke
				(width 0.1)
				(type default)
			)
			(layer "B.Fab")
		)
		(fp_line
			(start 1.1049 -0.724916)
			(end 1.1049 0.724916)
			(stroke
				(width 0.1)
				(type default)
			)
			(layer "B.Fab")
		)
		(pad "1" smd rect
			(at 0.889 0 270)
			(size 1.016 1.27)
			(layers "B.Cu" "B.Mask" "B.Paste")
			(net "PVDDIO_P0")
		)
		(pad "2" smd rect
			(at -0.889 0 270)
			(size 1.016 1.27)
			(layers "B.Cu" "B.Mask" "B.Paste")
			(net "GND")
		)
	)
	(footprint ""
		(layer "B.Cu")
		(at 100.144834 -271.903952 90)
		(property "Reference" "C2382"
			(at 0 0 90)
			(layer "B.SilkS")
			(hide yes)
			(effects
				(font
					(size 1.27 1.27)
				)
				(justify mirror)
			)
		)
		(property "Value" ""
			(at 0 0 90)
			(layer "B.Fab")
			(effects
				(font
					(size 1.27 1.27)
				)
				(justify mirror)
			)
		)
		(duplicate_pad_numbers_are_jumpers no)
		(fp_line
			(start 0.7874 -0.4064)
			(end -0.7874 -0.4064)
			(stroke
				(width 0.1524)
				(type default)
			)
			(layer "B.SilkS")
		)
		(fp_line
			(start -0.7874 -0.4064)
			(end -0.7874 0.4064)
			(stroke
				(width 0.1524)
				(type default)
			)
			(layer "B.SilkS")
		)
		(fp_line
			(start 0.7874 0.4064)
			(end 0.7874 -0.4064)
			(stroke
				(width 0.1524)
				(type default)
			)
			(layer "B.SilkS")
		)
		(fp_line
			(start -0.7874 0.4064)
			(end 0.7874 0.4064)
			(stroke
				(width 0.1524)
				(type default)
			)
			(layer "B.SilkS")
		)
		(fp_line
			(start 0.67945 -0.305054)
			(end 0.12065 -0.305054)
			(stroke
				(width 0.1)
				(type default)
			)
			(layer "B.Fab")
		)
		(fp_line
			(start 0.12065 -0.305054)
			(end 0.12065 -0.2794)
			(stroke
				(width 0.1)
				(type default)
			)
			(layer "B.Fab")
		)
		(fp_line
			(start -0.12065 -0.3048)
			(end -0.67945 -0.3048)
			(stroke
				(width 0.1)
				(type default)
			)
			(layer "B.Fab")
		)
		(fp_line
			(start -0.67945 -0.3048)
			(end -0.67945 0.3048)
			(stroke
				(width 0.1)
				(type default)
			)
			(layer "B.Fab")
		)
		(fp_line
			(start 0.12065 -0.2794)
			(end -0.12065 -0.2794)
			(stroke
				(width 0.1)
				(type default)
			)
			(layer "B.Fab")
		)
		(fp_line
			(start -0.12065 -0.2794)
			(end -0.12065 -0.3048)
			(stroke
				(width 0.1)
				(type default)
			)
			(layer "B.Fab")
		)
		(fp_line
			(start 0.12065 0.2794)
			(end 0.12065 0.3048)
			(stroke
				(width 0.1)
				(type default)
			)
			(layer "B.Fab")
		)
		(fp_line
			(start -0.120396 0.2794)
			(end 0.12065 0.2794)
			(stroke
				(width 0.1)
				(type default)
			)
			(layer "B.Fab")
		)
		(fp_line
			(start 0.67945 0.3048)
			(end 0.67945 -0.305054)
			(stroke
				(width 0.1)
				(type default)
			)
			(layer "B.Fab")
		)
		(fp_line
			(start 0.12065 0.3048)
			(end 0.67945 0.3048)
			(stroke
				(width 0.1)
				(type default)
			)
			(layer "B.Fab")
		)
		(fp_line
			(start -0.120396 0.3048)
			(end -0.120396 0.2794)
			(stroke
				(width 0.1)
				(type default)
			)
			(layer "B.Fab")
		)
		(fp_line
			(start -0.67945 0.3048)
			(end -0.120396 0.3048)
			(stroke
				(width 0.1)
				(type default)
			)
			(layer "B.Fab")
		)
		(pad "1" smd circle
			(at 0.40005 0 270)
			(size 0 0)
			(layers "B.Cu" "B.Mask" "B.Paste")
			(net "PVDDCR_CPU1_P1")
		)
		(pad "2" smd circle
			(at -0.40005 0 270)
			(size 0 0)
			(layers "B.Cu" "B.Mask" "B.Paste")
			(net "GND")
		)
	)
	(footprint ""
		(layer "B.Cu")
		(at 457.702666 -389.23087 -90)
		(property "Reference" "PC6806"
			(at 0 0 90)
			(layer "B.SilkS")
			(hide yes)
			(effects
				(font
					(size 1.27 1.27)
				)
				(justify mirror)
			)
		)
		(property "Value" ""
			(at 0 0 90)
			(layer "B.Fab")
			(effects
				(font
					(size 1.27 1.27)
				)
				(justify mirror)
			)
		)
		(duplicate_pad_numbers_are_jumpers no)
		(fp_line
			(start -0.7874 0.4064)
			(end 0.7874 0.4064)
			(stroke
				(width 0.1524)
				(type default)
			)
			(layer "B.SilkS")
		)
		(fp_line
			(start 0.7874 0.4064)
			(end 0.7874 -0.4064)
			(stroke
				(width 0.1524)
				(type default)
			)
			(layer "B.SilkS")
		)
		(fp_line
			(start -0.7874 -0.4064)
			(end -0.7874 0.4064)
			(stroke
				(width 0.1524)
				(type default)
			)
			(layer "B.SilkS")
		)
		(fp_line
			(start 0.7874 -0.4064)
			(end -0.7874 -0.4064)
			(stroke
				(width 0.1524)
				(type default)
			)
			(layer "B.SilkS")
		)
		(fp_line
			(start -0.67945 0.3048)
			(end -0.120396 0.3048)
			(stroke
				(width 0.1)
				(type default)
			)
			(layer "B.Fab")
		)
		(fp_line
			(start -0.120396 0.3048)
			(end -0.120396 0.2794)
			(stroke
				(width 0.1)
				(type default)
			)
			(layer "B.Fab")
		)
		(fp_line
			(start 0.12065 0.3048)
			(end 0.67945 0.3048)
			(stroke
				(width 0.1)
				(type default)
			)
			(layer "B.Fab")
		)
		(fp_line
			(start 0.67945 0.3048)
			(end 0.67945 -0.305054)
			(stroke
				(width 0.1)
				(type default)
			)
			(layer "B.Fab")
		)
		(fp_line
			(start -0.120396 0.2794)
			(end 0.12065 0.2794)
			(stroke
				(width 0.1)
				(type default)
			)
			(layer "B.Fab")
		)
		(fp_line
			(start 0.12065 0.2794)
			(end 0.12065 0.3048)
			(stroke
				(width 0.1)
				(type default)
			)
			(layer "B.Fab")
		)
		(fp_line
			(start -0.12065 -0.2794)
			(end -0.12065 -0.3048)
			(stroke
				(width 0.1)
				(type default)
			)
			(layer "B.Fab")
		)
		(fp_line
			(start 0.12065 -0.2794)
			(end -0.12065 -0.2794)
			(stroke
				(width 0.1)
				(type default)
			)
			(layer "B.Fab")
		)
		(fp_line
			(start -0.67945 -0.3048)
			(end -0.67945 0.3048)
			(stroke
				(width 0.1)
				(type default)
			)
			(layer "B.Fab")
		)
		(fp_line
			(start -0.12065 -0.3048)
			(end -0.67945 -0.3048)
			(stroke
				(width 0.1)
				(type default)
			)
			(layer "B.Fab")
		)
		(fp_line
			(start 0.12065 -0.305054)
			(end 0.12065 -0.2794)
			(stroke
				(width 0.1)
				(type default)
			)
			(layer "B.Fab")
		)
		(fp_line
			(start 0.67945 -0.305054)
			(end 0.12065 -0.305054)
			(stroke
				(width 0.1)
				(type default)
			)
			(layer "B.Fab")
		)
		(pad "1" smd circle
			(at 0.40005 0 90)
			(size 0 0)
			(layers "B.Cu" "B.Mask" "B.Paste")
			(net "P0V9_CPU0_RT_2D")
		)
		(pad "2" smd circle
			(at -0.40005 0 90)
			(size 0 0)
			(layers "B.Cu" "B.Mask" "B.Paste")
			(net "GND")
		)
	)
)
